(kicad_pcb
	(version 20260206)
	(generator "pcbnew")
	(generator_version "10.0")
	(general
		(thickness 1.6)
		(legacy_teardrops no)
	)
	(paper "A4")
	(title_block
		(title "12092022_DA0F0TFB6D0_F0T_FAN_BOARD_MP5048_D_brd_v02_OCP.brd")
		(comment 1 "Grand Teton / footprints 780-785 of 924")
	)
	(layers
		(0 "F.Cu" signal "TOP")
		(4 "In1.Cu" signal "GND")
		(6 "In2.Cu" signal "IN1")
		(8 "In3.Cu" signal "IN2")
		(10 "In4.Cu" signal "GND1")
		(2 "B.Cu" signal "BOTTOM")
		(9 "F.Adhes" user "F.Adhesive")
		(11 "B.Adhes" user "B.Adhesive")
		(13 "F.Paste" user "Package Geometry/Pastemask Top")
		(15 "B.Paste" user "Package Geometry/Pastemask Bottom")
		(5 "F.SilkS" user "Ref Des/Silkscreen Top")
		(7 "B.SilkS" user "Ref Des/Silkscreen Bottom")
		(1 "F.Mask" user "Board Geometry/Soldermask Top")
		(3 "B.Mask" user "Board Geometry/Soldermask Bottom")
		(17 "Dwgs.User" user "User.Drawings")
		(19 "Cmts.User" user "User.Comments")
		(21 "Eco1.User" user "User.Eco1")
		(23 "Eco2.User" user "User.Eco2")
		(25 "Edge.Cuts" user "Board Geometry/Outline")
		(27 "Margin" user)
		(31 "F.CrtYd" user "Package Geometry/Place Bound Top")
		(29 "B.CrtYd" user "Package Geometry/Place Bound Bottom")
		(35 "F.Fab" user "Ref Des/Assembly Top")
		(33 "B.Fab" user "Ref Des/Assembly Bottom")
	)
	(footprint ""
		(layer "B.Cu")
		(at 6.107176 -45.9232)
		(property "Reference" "C2110"
			(at 0 0 0)
			(layer "B.SilkS")
			(hide yes)
			(effects
				(font
					(size 1.27 1.27)
				)
				(justify mirror)
			)
		)
		(property "Value" ""
			(at 0 0 0)
			(layer "B.Fab")
			(effects
				(font
					(size 1.27 1.27)
				)
				(justify mirror)
			)
		)
		(duplicate_pad_numbers_are_jumpers no)
		(fp_line
			(start -2.2098 -0.9398)
			(end -2.2098 0.9398)
			(stroke
				(width 0.1524)
				(type default)
			)
			(layer "B.SilkS")
		)
		(fp_line
			(start -2.2098 0.9398)
			(end 2.2098 0.9398)
			(stroke
				(width 0.1524)
				(type default)
			)
			(layer "B.SilkS")
		)
		(fp_line
			(start 2.2098 -0.9398)
			(end -2.2098 -0.9398)
			(stroke
				(width 0.1524)
				(type default)
			)
			(layer "B.SilkS")
		)
		(fp_line
			(start 2.2098 0.9398)
			(end 2.2098 -0.9398)
			(stroke
				(width 0.1524)
				(type default)
			)
			(layer "B.SilkS")
		)
		(fp_line
			(start -1.700022 -0.899922)
			(end -1.700022 0.899922)
			(stroke
				(width 0.1)
				(type default)
			)
			(layer "B.Fab")
		)
		(fp_line
			(start -1.700022 0.899922)
			(end 1.700022 0.899922)
			(stroke
				(width 0.1)
				(type default)
			)
			(layer "B.Fab")
		)
		(fp_line
			(start 1.700022 -0.899922)
			(end -1.700022 -0.899922)
			(stroke
				(width 0.1)
				(type default)
			)
			(layer "B.Fab")
		)
		(fp_line
			(start 1.700022 0.899922)
			(end 1.700022 -0.899922)
			(stroke
				(width 0.1)
				(type default)
			)
			(layer "B.Fab")
		)
		(pad "1" smd rect
			(at 1.4732 0)
			(size 1.1684 1.5748)
			(layers "B.Cu" "B.Mask" "B.Paste")
			(net "P52V_FAN_4")
		)
		(pad "2" smd rect
			(at -1.4732 0)
			(size 1.1684 1.5748)
			(layers "B.Cu" "B.Mask" "B.Paste")
			(net "GND")
		)
	)
	(footprint ""
		(layer "B.Cu")
		(at 17.653 -127.381 180)
		(property "Reference" "R5436"
			(at 0 0 0)
			(layer "B.SilkS")
			(hide yes)
			(effects
				(font
					(size 1.27 1.27)
				)
				(justify mirror)
			)
		)
		(property "Value" ""
			(at 0 0 0)
			(layer "B.Fab")
			(effects
				(font
					(size 1.27 1.27)
				)
				(justify mirror)
			)
		)
		(duplicate_pad_numbers_are_jumpers no)
		(fp_line
			(start 0.7874 0.4064)
			(end 0.7874 -0.4064)
			(stroke
				(width 0.1524)
				(type default)
			)
			(layer "B.SilkS")
		)
		(fp_line
			(start 0.7874 -0.4064)
			(end -0.7874 -0.4064)
			(stroke
				(width 0.1524)
				(type default)
			)
			(layer "B.SilkS")
		)
		(fp_line
			(start -0.7874 0.4064)
			(end 0.7874 0.4064)
			(stroke
				(width 0.1524)
				(type default)
			)
			(layer "B.SilkS")
		)
		(fp_line
			(start -0.7874 -0.4064)
			(end -0.7874 0.4064)
			(stroke
				(width 0.1524)
				(type default)
			)
			(layer "B.SilkS")
		)
		(fp_line
			(start 0.67945 0.3048)
			(end 0.67945 -0.305054)
			(stroke
				(width 0.1)
				(type default)
			)
			(layer "B.Fab")
		)
		(fp_line
			(start 0.67945 -0.305054)
			(end 0.12065 -0.305054)
			(stroke
				(width 0.1)
				(type default)
			)
			(layer "B.Fab")
		)
		(fp_line
			(start 0.12065 0.3048)
			(end 0.67945 0.3048)
			(stroke
				(width 0.1)
				(type default)
			)
			(layer "B.Fab")
		)
		(fp_line
			(start 0.12065 0.2794)
			(end 0.12065 0.3048)
			(stroke
				(width 0.1)
				(type default)
			)
			(layer "B.Fab")
		)
		(fp_line
			(start 0.12065 -0.2794)
			(end -0.12065 -0.2794)
			(stroke
				(width 0.1)
				(type default)
			)
			(layer "B.Fab")
		)
		(fp_line
			(start 0.12065 -0.305054)
			(end 0.12065 -0.2794)
			(stroke
				(width 0.1)
				(type default)
			)
			(layer "B.Fab")
		)
		(fp_line
			(start -0.120396 0.3048)
			(end -0.120396 0.2794)
			(stroke
				(width 0.1)
				(type default)
			)
			(layer "B.Fab")
		)
		(fp_line
			(start -0.120396 0.2794)
			(end 0.12065 0.2794)
			(stroke
				(width 0.1)
				(type default)
			)
			(layer "B.Fab")
		)
		(fp_line
			(start -0.12065 -0.2794)
			(end -0.12065 -0.3048)
			(stroke
				(width 0.1)
				(type default)
			)
			(layer "B.Fab")
		)
		(fp_line
			(start -0.12065 -0.3048)
			(end -0.67945 -0.3048)
			(stroke
				(width 0.1)
				(type default)
			)
			(layer "B.Fab")
		)
		(fp_line
			(start -0.67945 0.3048)
			(end -0.120396 0.3048)
			(stroke
				(width 0.1)
				(type default)
			)
			(layer "B.Fab")
		)
		(fp_line
			(start -0.67945 -0.3048)
			(end -0.67945 0.3048)
			(stroke
				(width 0.1)
				(type default)
			)
			(layer "B.Fab")
		)
		(pad "1" smd rect
			(at 0.40005 0 180)
			(size 0.4572 0.508)
			(layers "B.Cu" "B.Mask" "B.Paste")
			(net "FAN_5_TACH_IL")
		)
		(pad "2" smd rect
			(at -0.40005 0 180)
			(size 0.4572 0.508)
			(layers "B.Cu" "B.Mask" "B.Paste")
			(net "GND")
		)
	)
	(footprint ""
		(layer "B.Cu")
		(at 33.4518 -279.0444)
		(property "Reference" "C2096"
			(at 0 0 0)
			(layer "B.SilkS")
			(hide yes)
			(effects
				(font
					(size 1.27 1.27)
				)
				(justify mirror)
			)
		)
		(property "Value" ""
			(at 0 0 0)
			(layer "B.Fab")
			(effects
				(font
					(size 1.27 1.27)
				)
				(justify mirror)
			)
		)
		(duplicate_pad_numbers_are_jumpers no)
		(fp_line
			(start -2.2098 -0.9398)
			(end -2.2098 0.9398)
			(stroke
				(width 0.1524)
				(type default)
			)
			(layer "B.SilkS")
		)
		(fp_line
			(start -2.2098 0.9398)
			(end 2.2098 0.9398)
			(stroke
				(width 0.1524)
				(type default)
			)
			(layer "B.SilkS")
		)
		(fp_line
			(start 2.2098 -0.9398)
			(end -2.2098 -0.9398)
			(stroke
				(width 0.1524)
				(type default)
			)
			(layer "B.SilkS")
		)
		(fp_line
			(start 2.2098 0.9398)
			(end 2.2098 -0.9398)
			(stroke
				(width 0.1524)
				(type default)
			)
			(layer "B.SilkS")
		)
		(fp_line
			(start -1.700022 -0.899922)
			(end -1.700022 0.899922)
			(stroke
				(width 0.1)
				(type default)
			)
			(layer "B.Fab")
		)
		(fp_line
			(start -1.700022 0.899922)
			(end 1.700022 0.899922)
			(stroke
				(width 0.1)
				(type default)
			)
			(layer "B.Fab")
		)
		(fp_line
			(start 1.700022 -0.899922)
			(end -1.700022 -0.899922)
			(stroke
				(width 0.1)
				(type default)
			)
			(layer "B.Fab")
		)
		(fp_line
			(start 1.700022 0.899922)
			(end 1.700022 -0.899922)
			(stroke
				(width 0.1)
				(type default)
			)
			(layer "B.Fab")
		)
		(pad "1" smd rect
			(at 1.4732 0)
			(size 1.1684 1.5748)
			(layers "B.Cu" "B.Mask" "B.Paste")
			(net "P52V_FAN_0")
		)
		(pad "2" smd rect
			(at -1.4732 0)
			(size 1.1684 1.5748)
			(layers "B.Cu" "B.Mask" "B.Paste")
			(net "GND")
		)
	)
	(footprint ""
		(layer "B.Cu")
		(at 6.223 -249.047 180)
		(property "Reference" "PR69"
			(at 0 0 0)
			(layer "B.SilkS")
			(hide yes)
			(effects
				(font
					(size 1.27 1.27)
				)
				(justify mirror)
			)
		)
		(property "Value" ""
			(at 0 0 0)
			(layer "B.Fab")
			(effects
				(font
					(size 1.27 1.27)
				)
				(justify mirror)
			)
		)
		(duplicate_pad_numbers_are_jumpers no)
		(fp_line
			(start 0.7874 0.4064)
			(end 0.7874 -0.4064)
			(stroke
				(width 0.1524)
				(type default)
			)
			(layer "B.SilkS")
		)
		(fp_line
			(start 0.7874 -0.4064)
			(end -0.7874 -0.4064)
			(stroke
				(width 0.1524)
				(type default)
			)
			(layer "B.SilkS")
		)
		(fp_line
			(start -0.7874 0.4064)
			(end 0.7874 0.4064)
			(stroke
				(width 0.1524)
				(type default)
			)
			(layer "B.SilkS")
		)
		(fp_line
			(start -0.7874 -0.4064)
			(end -0.7874 0.4064)
			(stroke
				(width 0.1524)
				(type default)
			)
			(layer "B.SilkS")
		)
		(fp_line
			(start 0.67945 0.3048)
			(end 0.67945 -0.305054)
			(stroke
				(width 0.1)
				(type default)
			)
			(layer "B.Fab")
		)
		(fp_line
			(start 0.67945 -0.305054)
			(end 0.12065 -0.305054)
			(stroke
				(width 0.1)
				(type default)
			)
			(layer "B.Fab")
		)
		(fp_line
			(start 0.12065 0.3048)
			(end 0.67945 0.3048)
			(stroke
				(width 0.1)
				(type default)
			)
			(layer "B.Fab")
		)
		(fp_line
			(start 0.12065 0.2794)
			(end 0.12065 0.3048)
			(stroke
				(width 0.1)
				(type default)
			)
			(layer "B.Fab")
		)
		(fp_line
			(start 0.12065 -0.2794)
			(end -0.12065 -0.2794)
			(stroke
				(width 0.1)
				(type default)
			)
			(layer "B.Fab")
		)
		(fp_line
			(start 0.12065 -0.305054)
			(end 0.12065 -0.2794)
			(stroke
				(width 0.1)
				(type default)
			)
			(layer "B.Fab")
		)
		(fp_line
			(start -0.120396 0.3048)
			(end -0.120396 0.2794)
			(stroke
				(width 0.1)
				(type default)
			)
			(layer "B.Fab")
		)
		(fp_line
			(start -0.120396 0.2794)
			(end 0.12065 0.2794)
			(stroke
				(width 0.1)
				(type default)
			)
			(layer "B.Fab")
		)
		(fp_line
			(start -0.12065 -0.2794)
			(end -0.12065 -0.3048)
			(stroke
				(width 0.1)
				(type default)
			)
			(layer "B.Fab")
		)
		(fp_line
			(start -0.12065 -0.3048)
			(end -0.67945 -0.3048)
			(stroke
				(width 0.1)
				(type default)
			)
			(layer "B.Fab")
		)
		(fp_line
			(start -0.67945 0.3048)
			(end -0.120396 0.3048)
			(stroke
				(width 0.1)
				(type default)
			)
			(layer "B.Fab")
		)
		(fp_line
			(start -0.67945 -0.3048)
			(end -0.67945 0.3048)
			(stroke
				(width 0.1)
				(type default)
			)
			(layer "B.Fab")
		)
		(pad "1" smd circle
			(at 0.40005 0)
			(size 0 0)
			(layers "B.Cu" "B.Mask" "B.Paste")
			(net "FAN_6_CLREF")
		)
		(pad "2" smd circle
			(at -0.40005 0)
			(size 0 0)
			(layers "B.Cu" "B.Mask" "B.Paste")
			(net "GND")
		)
	)
	(footprint ""
		(layer "B.Cu")
		(at 6.223 -250.063)
		(property "Reference" "PC3124"
			(at 0 0 0)
			(layer "B.SilkS")
			(hide yes)
			(effects
				(font
					(size 1.27 1.27)
				)
				(justify mirror)
			)
		)
		(property "Value" ""
			(at 0 0 0)
			(layer "B.Fab")
			(effects
				(font
					(size 1.27 1.27)
				)
				(justify mirror)
			)
		)
		(duplicate_pad_numbers_are_jumpers no)
		(fp_line
			(start -0.7874 -0.4064)
			(end -0.7874 0.4064)
			(stroke
				(width 0.1524)
				(type default)
			)
			(layer "B.SilkS")
		)
		(fp_line
			(start -0.7874 0.4064)
			(end 0.7874 0.4064)
			(stroke
				(width 0.1524)
				(type default)
			)
			(layer "B.SilkS")
		)
		(fp_line
			(start 0.7874 -0.4064)
			(end -0.7874 -0.4064)
			(stroke
				(width 0.1524)
				(type default)
			)
			(layer "B.SilkS")
		)
		(fp_line
			(start 0.7874 0.4064)
			(end 0.7874 -0.4064)
			(stroke
				(width 0.1524)
				(type default)
			)
			(layer "B.SilkS")
		)
		(fp_line
			(start -0.67945 -0.3048)
			(end -0.67945 0.3048)
			(stroke
				(width 0.1)
				(type default)
			)
			(layer "B.Fab")
		)
		(fp_line
			(start -0.67945 0.3048)
			(end -0.120396 0.3048)
			(stroke
				(width 0.1)
				(type default)
			)
			(layer "B.Fab")
		)
		(fp_line
			(start -0.12065 -0.3048)
			(end -0.67945 -0.3048)
			(stroke
				(width 0.1)
				(type default)
			)
			(layer "B.Fab")
		)
		(fp_line
			(start -0.12065 -0.2794)
			(end -0.12065 -0.3048)
			(stroke
				(width 0.1)
				(type default)
			)
			(layer "B.Fab")
		)
		(fp_line
			(start -0.120396 0.2794)
			(end 0.12065 0.2794)
			(stroke
				(width 0.1)
				(type default)
			)
			(layer "B.Fab")
		)
		(fp_line
			(start -0.120396 0.3048)
			(end -0.120396 0.2794)
			(stroke
				(width 0.1)
				(type default)
			)
			(layer "B.Fab")
		)
		(fp_line
			(start 0.12065 -0.305054)
			(end 0.12065 -0.2794)
			(stroke
				(width 0.1)
				(type default)
			)
			(layer "B.Fab")
		)
		(fp_line
			(start 0.12065 -0.2794)
			(end -0.12065 -0.2794)
			(stroke
				(width 0.1)
				(type default)
			)
			(layer "B.Fab")
		)
		(fp_line
			(start 0.12065 0.2794)
			(end 0.12065 0.3048)
			(stroke
				(width 0.1)
				(type default)
			)
			(layer "B.Fab")
		)
		(fp_line
			(start 0.12065 0.3048)
			(end 0.67945 0.3048)
			(stroke
				(width 0.1)
				(type default)
			)
			(layer "B.Fab")
		)
		(fp_line
			(start 0.67945 -0.305054)
			(end 0.12065 -0.305054)
			(stroke
				(width 0.1)
				(type default)
			)
			(layer "B.Fab")
		)
		(fp_line
			(start 0.67945 0.3048)
			(end 0.67945 -0.305054)
			(stroke
				(width 0.1)
				(type default)
			)
			(layer "B.Fab")
		)
		(pad "1" smd circle
			(at 0.40005 0 180)
			(size 0 0)
			(layers "B.Cu" "B.Mask" "B.Paste")
			(net "GND")
		)
		(pad "2" smd circle
			(at -0.40005 0 180)
			(size 0 0)
			(layers "B.Cu" "B.Mask" "B.Paste")
			(net "FAN_6_CLREF")
		)
	)
	(footprint ""
		(layer "B.Cu")
		(at 46.6852 -274.9804 -90)
		(property "Reference" "PD1"
			(at 4.7752 -3.749548 270)
			(unlocked yes)
			(layer "B.SilkS")
			(effects
				(font
					(size 0.7874 0.5842)
					(thickness 0.1524)
				)
				(justify left mirror)
			)
		)
		(property "Value" ""
			(at 0 0 90)
			(layer "B.Fab")
			(effects
				(font
					(size 1.27 1.27)
				)
				(justify mirror)
			)
		)
		(duplicate_pad_numbers_are_jumpers no)
		(fp_line
			(start -5.334 3.109976)
			(end -4.8133 3.109976)
			(stroke
				(width 0.1524)
				(type default)
			)
			(layer "B.SilkS")
		)
		(fp_line
			(start -5.334 3.109976)
			(end -5.334 0)
			(stroke
				(width 0.1524)
				(type default)
			)
			(layer "B.SilkS")
		)
		(fp_line
			(start -5.207 3.109976)
			(end -5.207 -3.109976)
			(stroke
				(width 0.1524)
				(type default)
			)
			(layer "B.SilkS")
		)
		(fp_line
			(start -5.1308 3.109976)
			(end -5.1308 -3.109976)
			(stroke
				(width 0.1524)
				(type default)
			)
			(layer "B.SilkS")
		)
		(fp_line
			(start -5.0292 3.109976)
			(end -5.0292 -3.109976)
			(stroke
				(width 0.1524)
				(type default)
			)
			(layer "B.SilkS")
		)
		(fp_line
			(start -4.9276 3.109976)
			(end -4.9276 -3.109976)
			(stroke
				(width 0.1524)
				(type default)
			)
			(layer "B.SilkS")
		)
		(fp_line
			(start -4.826 3.109976)
			(end 4.826 3.109976)
			(stroke
				(width 0.1524)
				(type default)
			)
			(layer "B.SilkS")
		)
		(fp_line
			(start 4.826 3.109976)
			(end 4.826 0)
			(stroke
				(width 0.1524)
				(type default)
			)
			(layer "B.SilkS")
		)
		(fp_line
			(start -1.143 1.397)
			(end -1.143 -1.397)
			(stroke
				(width 0.1524)
				(type default)
			)
			(layer "B.SilkS")
		)
		(fp_line
			(start 1.016 1.016)
			(end -1.016 0)
			(stroke
				(width 0.1524)
				(type default)
			)
			(layer "B.SilkS")
		)
		(fp_line
			(start -5.334 0)
			(end -5.334 -3.109976)
			(stroke
				(width 0.1524)
				(type default)
			)
			(layer "B.SilkS")
		)
		(fp_line
			(start -4.826 0)
			(end -4.826 3.109976)
			(stroke
				(width 0.1524)
				(type default)
			)
			(layer "B.SilkS")
		)
		(fp_line
			(start -1.143 0)
			(end -1.8034 0)
			(stroke
				(width 0.1524)
				(type default)
			)
			(layer "B.SilkS")
		)
		(fp_line
			(start -1.143 0)
			(end 1.016 -1.016)
			(stroke
				(width 0.1524)
				(type default)
			)
			(layer "B.SilkS")
		)
		(fp_line
			(start 1.0922 0)
			(end 1.7018 0)
			(stroke
				(width 0.1524)
				(type default)
			)
			(layer "B.SilkS")
		)
		(fp_line
			(start 4.826 0)
			(end 4.826 -3.109976)
			(stroke
				(width 0.1524)
				(type default)
			)
			(layer "B.SilkS")
		)
		(fp_line
			(start 1.016 -1.016)
			(end 1.016 1.016)
			(stroke
				(width 0.1524)
				(type default)
			)
			(layer "B.SilkS")
		)
		(fp_line
			(start -4.826 -3.109976)
			(end -4.826 0)
			(stroke
				(width 0.1524)
				(type default)
			)
			(layer "B.SilkS")
		)
		(fp_line
			(start -4.8133 -3.109976)
			(end -5.3467 -3.109976)
			(stroke
				(width 0.1524)
				(type default)
			)
			(layer "B.SilkS")
		)
		(fp_line
			(start 4.826 -3.109976)
			(end -4.826 -3.109976)
			(stroke
				(width 0.1524)
				(type default)
			)
			(layer "B.SilkS")
		)
		(fp_line
			(start -3.554984 3.109976)
			(end 3.554984 3.109976)
			(stroke
				(width 0.1)
				(type default)
			)
			(layer "B.Fab")
		)
		(fp_line
			(start 3.554984 3.109976)
			(end 3.554984 -3.109976)
			(stroke
				(width 0.1)
				(type default)
			)
			(layer "B.Fab")
		)
		(fp_line
			(start -1.143 1.397)
			(end -1.143 -1.397)
			(stroke
				(width 0.1)
				(type default)
			)
			(layer "B.Fab")
		)
		(fp_line
			(start 1.016 1.016)
			(end -1.016 0)
			(stroke
				(width 0.1)
				(type default)
			)
			(layer "B.Fab")
		)
		(fp_line
			(start -1.143 0)
			(end -1.8034 0)
			(stroke
				(width 0.1)
				(type default)
			)
			(layer "B.Fab")
		)
		(fp_line
			(start -1.143 0)
			(end 1.016 -1.016)
			(stroke
				(width 0.1)
				(type default)
			)
			(layer "B.Fab")
		)
		(fp_line
			(start 1.0922 0)
			(end 1.7018 0)
			(stroke
				(width 0.1)
				(type default)
			)
			(layer "B.Fab")
		)
		(fp_line
			(start 1.016 -1.016)
			(end 1.016 1.016)
			(stroke
				(width 0.1)
				(type default)
			)
			(layer "B.Fab")
		)
		(fp_line
			(start -3.554984 -3.109976)
			(end -3.554984 3.109976)
			(stroke
				(width 0.1)
				(type default)
			)
			(layer "B.Fab")
		)
		(fp_line
			(start 3.554984 -3.109976)
			(end -3.554984 -3.109976)
			(stroke
				(width 0.1)
				(type default)
			)
			(layer "B.Fab")
		)
		(fp_text user "+"
			(at 4.8006 2.45745 90)
			(unlocked yes)
			(layer "B.SilkS")
			(effects
				(font
					(size 1.905 1.4224)
					(thickness 0.1524)
				)
				(justify left mirror)
			)
		)
		(fp_text user "-"
			(at -7.4422 0.12065 90)
			(unlocked yes)
			(layer "B.SilkS")
			(effects
				(font
					(size 1.905 1.4224)
					(thickness 0.1524)
				)
				(justify left mirror)
			)
		)
		(fp_text user "-"
			(at -6.6802 0.22225 90)
			(unlocked yes)
			(layer "B.Fab")
			(effects
				(font
					(size 1.905 1.4224)
					(thickness 0.1524)
				)
				(justify left mirror)
			)
		)
		(fp_text user "+"
			(at 4.5466 0.19685 90)
			(unlocked yes)
			(layer "B.Fab")
			(effects
				(font
					(size 1.905 1.4224)
					(thickness 0.1524)
				)
				(justify left mirror)
			)
		)
		(pad "A" smd rect
			(at 3.400044 0 270)
			(size 2.5146 3.302)
			(layers "B.Cu" "B.Mask" "B.Paste")
			(net "GND")
		)
		(pad "C" smd rect
			(at -3.400044 0 270)
			(size 2.5146 3.302)
			(layers "B.Cu" "B.Mask" "B.Paste")
			(net "P52V_FAN_0")
		)
	)
)
